# SCM (Grand Teton) — schematic netlist excerpt (pin names and nets, part order shuffled) for the footprints in the layout excerpt that follows; sources: Cadence DE-HDL packaged netlist, KiCad conversion of 12092022_DA0F0TMDCD0_F0T_Management_Board_D_brd_V3_OCP.brd

R450  Q_RES  0 5% CHIP  pkg 0402LF  page 22 : A = RST_BMC_SELF_HW ; B = RST_BMC_SELF_HW_R3
R292  Q_RES  0 5% CHIP  pkg 0402LF  page 51 : A = PWRGD_P5V_AUX_R ; B = PWRGD_P5V_AUX

(kicad_pcb
	(version 20260206)
	(generator "pcbnew")
	(generator_version "10.0")
	(general
		(thickness 1.6)
		(legacy_teardrops no)
	)
	(paper "A4")
	(title_block
		(title "12092022_DA0F0TMDCD0_F0T_Management_Board_D_brd_V3_OCP.brd")
		(comment 1 "Grand Teton / footprints 1392-1393 of 1440")
	)
	(layers
		(0 "F.Cu" signal "TOP")
		(4 "In1.Cu" signal "GND")
		(6 "In2.Cu" signal "IN1")
		(8 "In3.Cu" signal "GND1")
		(10 "In4.Cu" signal "IN2")
		(12 "In5.Cu" signal "VCC")
		(14 "In6.Cu" signal "VCC1")
		(16 "In7.Cu" signal "IN3")
		(18 "In8.Cu" signal "GND2")
		(20 "In9.Cu" signal "IN4")
		(22 "In10.Cu" signal "GND3")
		(2 "B.Cu" signal "BOTTOM")
		(9 "F.Adhes" user "F.Adhesive")
		(11 "B.Adhes" user "B.Adhesive")
		(13 "F.Paste" user "Package Geometry/Pastemask Top")
		(15 "B.Paste" user "Package Geometry/Pastemask Bottom")
		(5 "F.SilkS" user "Ref Des/Silkscreen Top")
		(7 "B.SilkS" user "Ref Des/Silkscreen Bottom")
		(1 "F.Mask" user "Board Geometry/Soldermask Top")
		(3 "B.Mask" user "Board Geometry/Soldermask Bottom")
		(17 "Dwgs.User" user "User.Drawings")
		(19 "Cmts.User" user "User.Comments")
		(21 "Eco1.User" user "User.Eco1")
		(23 "Eco2.User" user "User.Eco2")
		(25 "Edge.Cuts" user "Board Geometry/Outline")
		(27 "Margin" user)
		(31 "F.CrtYd" user "Package Geometry/Place Bound Top")
		(29 "B.CrtYd" user "Package Geometry/Place Bound Bottom")
		(35 "F.Fab" user "Ref Des/Assembly Top")
		(33 "B.Fab" user "Ref Des/Assembly Bottom")
	)
	(footprint ""
		(layer "B.Cu")
		(at 12.32662 -56.00192 180)
		(property "Reference" "R292"
			(at 0 0 0)
			(layer "B.SilkS")
			(hide yes)
			(effects
				(font
					(size 1.27 1.27)
				)
				(justify mirror)
			)
		)
		(property "Value" ""
			(at 0 0 0)
			(layer "B.Fab")
			(effects
				(font
					(size 1.27 1.27)
				)
				(justify mirror)
			)
		)
		(duplicate_pad_numbers_are_jumpers no)
		(fp_line
			(start 0.7874 0.4064)
			(end 0.7874 -0.4064)
			(stroke
				(width 0.1524)
				(type default)
			)
			(layer "B.SilkS")
		)
		(fp_line
			(start 0.7874 -0.4064)
			(end -0.7874 -0.4064)
			(stroke
				(width 0.1524)
				(type default)
			)
			(layer "B.SilkS")
		)
		(fp_line
			(start -0.7874 0.4064)
			(end 0.7874 0.4064)
			(stroke
				(width 0.1524)
				(type default)
			)
			(layer "B.SilkS")
		)
		(fp_line
			(start -0.7874 -0.4064)
			(end -0.7874 0.4064)
			(stroke
				(width 0.1524)
				(type default)
			)
			(layer "B.SilkS")
		)
		(fp_line
			(start 0.67945 0.3048)
			(end 0.67945 -0.305054)
			(stroke
				(width 0.1)
				(type default)
			)
			(layer "B.Fab")
		)
		(fp_line
			(start 0.67945 -0.305054)
			(end 0.12065 -0.305054)
			(stroke
				(width 0.1)
				(type default)
			)
			(layer "B.Fab")
		)
		(fp_line
			(start 0.12065 0.3048)
			(end 0.67945 0.3048)
			(stroke
				(width 0.1)
				(type default)
			)
			(layer "B.Fab")
		)
		(fp_line
			(start 0.12065 0.2794)
			(end 0.12065 0.3048)
			(stroke
				(width 0.1)
				(type default)
			)
			(layer "B.Fab")
		)
		(fp_line
			(start 0.12065 -0.2794)
			(end -0.12065 -0.2794)
			(stroke
				(width 0.1)
				(type default)
			)
			(layer "B.Fab")
		)
		(fp_line
			(start 0.12065 -0.305054)
			(end 0.12065 -0.2794)
			(stroke
				(width 0.1)
				(type default)
			)
			(layer "B.Fab")
		)
		(fp_line
			(start -0.120396 0.3048)
			(end -0.120396 0.2794)
			(stroke
				(width 0.1)
				(type default)
			)
			(layer "B.Fab")
		)
		(fp_line
			(start -0.120396 0.2794)
			(end 0.12065 0.2794)
			(stroke
				(width 0.1)
				(type default)
			)
			(layer "B.Fab")
		)
		(fp_line
			(start -0.12065 -0.2794)
			(end -0.12065 -0.3048)
			(stroke
				(width 0.1)
				(type default)
			)
			(layer "B.Fab")
		)
		(fp_line
			(start -0.12065 -0.3048)
			(end -0.67945 -0.3048)
			(stroke
				(width 0.1)
				(type default)
			)
			(layer "B.Fab")
		)
		(fp_line
			(start -0.67945 0.3048)
			(end -0.120396 0.3048)
			(stroke
				(width 0.1)
				(type default)
			)
			(layer "B.Fab")
		)
		(fp_line
			(start -0.67945 -0.3048)
			(end -0.67945 0.3048)
			(stroke
				(width 0.1)
				(type default)
			)
			(layer "B.Fab")
		)
		(pad "1" smd circle
			(at 0.40005 0)
			(size 0 0)
			(layers "B.Cu" "B.Mask" "B.Paste")
			(net "PWRGD_P5V_AUX_R")
		)
		(pad "2" smd circle
			(at -0.40005 0)
			(size 0 0)
			(layers "B.Cu" "B.Mask" "B.Paste")
			(net "PWRGD_P5V_AUX")
		)
	)
	(footprint ""
		(layer "B.Cu")
		(at 32.004 -101.854 90)
		(property "Reference" "R450"
			(at 0 0 90)
			(layer "B.SilkS")
			(hide yes)
			(effects
				(font
					(size 1.27 1.27)
				)
				(justify mirror)
			)
		)
		(property "Value" ""
			(at 0 0 90)
			(layer "B.Fab")
			(effects
				(font
					(size 1.27 1.27)
				)
				(justify mirror)
			)
		)
		(duplicate_pad_numbers_are_jumpers no)
		(fp_line
			(start 0.7874 -0.4064)
			(end -0.7874 -0.4064)
			(stroke
				(width 0.1524)
				(type default)
			)
			(layer "B.SilkS")
		)
		(fp_line
			(start -0.7874 -0.4064)
			(end -0.7874 0.4064)
			(stroke
				(width 0.1524)
				(type default)
			)
			(layer "B.SilkS")
		)
		(fp_line
			(start 0.7874 0.4064)
			(end 0.7874 -0.4064)
			(stroke
				(width 0.1524)
				(type default)
			)
			(layer "B.SilkS")
		)
		(fp_line
			(start -0.7874 0.4064)
			(end 0.7874 0.4064)
			(stroke
				(width 0.1524)
				(type default)
			)
			(layer "B.SilkS")
		)
		(fp_line
			(start 0.67945 -0.305054)
			(end 0.12065 -0.305054)
			(stroke
				(width 0.1)
				(type default)
			)
			(layer "B.Fab")
		)
		(fp_line
			(start 0.12065 -0.305054)
			(end 0.12065 -0.2794)
			(stroke
				(width 0.1)
				(type default)
			)
			(layer "B.Fab")
		)
		(fp_line
			(start -0.12065 -0.3048)
			(end -0.67945 -0.3048)
			(stroke
				(width 0.1)
				(type default)
			)
			(layer "B.Fab")
		)
		(fp_line
			(start -0.67945 -0.3048)
			(end -0.67945 0.3048)
			(stroke
				(width 0.1)
				(type default)
			)
			(layer "B.Fab")
		)
		(fp_line
			(start 0.12065 -0.2794)
			(end -0.12065 -0.2794)
			(stroke
				(width 0.1)
				(type default)
			)
			(layer "B.Fab")
		)
		(fp_line
			(start -0.12065 -0.2794)
			(end -0.12065 -0.3048)
			(stroke
				(width 0.1)
				(type default)
			)
			(layer "B.Fab")
		)
		(fp_line
			(start 0.12065 0.2794)
			(end 0.12065 0.3048)
			(stroke
				(width 0.1)
				(type default)
			)
			(layer "B.Fab")
		)
		(fp_line
			(start -0.120396 0.2794)
			(end 0.12065 0.2794)
			(stroke
				(width 0.1)
				(type default)
			)
			(layer "B.Fab")
		)
		(fp_line
			(start 0.67945 0.3048)
			(end 0.67945 -0.305054)
			(stroke
				(width 0.1)
				(type default)
			)
			(layer "B.Fab")
		)
		(fp_line
			(start 0.12065 0.3048)
			(end 0.67945 0.3048)
			(stroke
				(width 0.1)
				(type default)
			)
			(layer "B.Fab")
		)
		(fp_line
			(start -0.120396 0.3048)
			(end -0.120396 0.2794)
			(stroke
				(width 0.1)
				(type default)
			)
			(layer "B.Fab")
		)
		(fp_line
			(start -0.67945 0.3048)
			(end -0.120396 0.3048)
			(stroke
				(width 0.1)
				(type default)
			)
			(layer "B.Fab")
		)
		(pad "1" smd circle
			(at 0.40005 0 270)
			(size 0 0)
			(layers "B.Cu" "B.Mask" "B.Paste")
			(net "RST_BMC_SELF_HW")
		)
		(pad "2" smd circle
			(at -0.40005 0 270)
			(size 0 0)
			(layers "B.Cu" "B.Mask" "B.Paste")
			(net "RST_BMC_SELF_HW_R3")
		)
	)
)
